(kicad_pcb
	(version 20260206)
	(generator "pcbnew")
	(generator_version "10.0")
	(general
		(thickness 1.6)
		(legacy_teardrops no)
	)
	(paper "A4")
	(title_block
		(title "01162023_DA0F0TEBIF0_F0T_Expander_BD_F_brd_V02_OCP.brd")
		(comment 1 "Grand Teton / footprints 7017-7023 of 9728")
	)
	(layers
		(0 "F.Cu" signal "TOP")
		(4 "In1.Cu" signal "GND")
		(6 "In2.Cu" signal "VCC")
		(8 "In3.Cu" signal "VCC1")
		(10 "In4.Cu" signal "GND1")
		(12 "In5.Cu" signal "IN1")
		(14 "In6.Cu" signal "GND2")
		(16 "In7.Cu" signal "IN2")
		(18 "In8.Cu" signal "GND3")
		(20 "In9.Cu" signal "IN3")
		(22 "In10.Cu" signal "GND4")
		(24 "In11.Cu" signal "IN4")
		(26 "In12.Cu" signal "GND5")
		(28 "In13.Cu" signal "IN5")
		(30 "In14.Cu" signal "GND6")
		(32 "In15.Cu" signal "IN6")
		(34 "In16.Cu" signal "GND7")
		(2 "B.Cu" signal "BOTTOM")
		(9 "F.Adhes" user "F.Adhesive")
		(11 "B.Adhes" user "B.Adhesive")
		(13 "F.Paste" user "Package Geometry/Pastemask Top")
		(15 "B.Paste" user "Package Geometry/Pastemask Bottom")
		(5 "F.SilkS" user "Ref Des/Silkscreen Top")
		(7 "B.SilkS" user "Ref Des/Silkscreen Bottom")
		(1 "F.Mask" user "Board Geometry/Soldermask Top")
		(3 "B.Mask" user "Board Geometry/Soldermask Bottom")
		(17 "Dwgs.User" user "User.Drawings")
		(19 "Cmts.User" user "User.Comments")
		(21 "Eco1.User" user "User.Eco1")
		(23 "Eco2.User" user "User.Eco2")
		(25 "Edge.Cuts" user "Board Geometry/Outline")
		(27 "Margin" user)
		(31 "F.CrtYd" user "Package Geometry/Place Bound Top")
		(29 "B.CrtYd" user "Package Geometry/Place Bound Bottom")
		(35 "F.Fab" user "Ref Des/Assembly Top")
		(33 "B.Fab" user "Ref Des/Assembly Bottom")
	)
	(footprint ""
		(layer "F.Cu")
		(at 32.411416 -286.844232 -90)
		(property "Reference" "R4564"
			(at 0 0 270)
			(layer "F.SilkS")
			(hide yes)
			(effects
				(font
					(size 1.27 1.27)
				)
			)
		)
		(property "Value" ""
			(at 0 0 270)
			(layer "F.Fab")
			(effects
				(font
					(size 1.27 1.27)
				)
			)
		)
		(duplicate_pad_numbers_are_jumpers no)
		(fp_line
			(start -0.7874 0.4064)
			(end -0.7874 -0.4064)
			(stroke
				(width 0.1524)
				(type default)
			)
			(layer "F.SilkS")
		)
		(fp_line
			(start 0.7874 0.4064)
			(end -0.7874 0.4064)
			(stroke
				(width 0.1524)
				(type default)
			)
			(layer "F.SilkS")
		)
		(fp_line
			(start -0.7874 -0.4064)
			(end 0.7874 -0.4064)
			(stroke
				(width 0.1524)
				(type default)
			)
			(layer "F.SilkS")
		)
		(fp_line
			(start 0.7874 -0.4064)
			(end 0.7874 0.4064)
			(stroke
				(width 0.1524)
				(type default)
			)
			(layer "F.SilkS")
		)
		(fp_line
			(start -0.67945 0.3048)
			(end -0.67945 -0.305054)
			(stroke
				(width 0.1)
				(type default)
			)
			(layer "F.Fab")
		)
		(fp_line
			(start -0.12065 0.3048)
			(end -0.67945 0.3048)
			(stroke
				(width 0.1)
				(type default)
			)
			(layer "F.Fab")
		)
		(fp_line
			(start 0.120396 0.3048)
			(end 0.120396 0.2794)
			(stroke
				(width 0.1)
				(type default)
			)
			(layer "F.Fab")
		)
		(fp_line
			(start 0.67945 0.3048)
			(end 0.120396 0.3048)
			(stroke
				(width 0.1)
				(type default)
			)
			(layer "F.Fab")
		)
		(fp_line
			(start -0.12065 0.2794)
			(end -0.12065 0.3048)
			(stroke
				(width 0.1)
				(type default)
			)
			(layer "F.Fab")
		)
		(fp_line
			(start 0.120396 0.2794)
			(end -0.12065 0.2794)
			(stroke
				(width 0.1)
				(type default)
			)
			(layer "F.Fab")
		)
		(fp_line
			(start -0.12065 -0.2794)
			(end 0.12065 -0.2794)
			(stroke
				(width 0.1)
				(type default)
			)
			(layer "F.Fab")
		)
		(fp_line
			(start 0.12065 -0.2794)
			(end 0.12065 -0.3048)
			(stroke
				(width 0.1)
				(type default)
			)
			(layer "F.Fab")
		)
		(fp_line
			(start 0.12065 -0.3048)
			(end 0.67945 -0.3048)
			(stroke
				(width 0.1)
				(type default)
			)
			(layer "F.Fab")
		)
		(fp_line
			(start 0.67945 -0.3048)
			(end 0.67945 0.3048)
			(stroke
				(width 0.1)
				(type default)
			)
			(layer "F.Fab")
		)
		(fp_line
			(start -0.67945 -0.305054)
			(end -0.12065 -0.305054)
			(stroke
				(width 0.1)
				(type default)
			)
			(layer "F.Fab")
		)
		(fp_line
			(start -0.12065 -0.305054)
			(end -0.12065 -0.2794)
			(stroke
				(width 0.1)
				(type default)
			)
			(layer "F.Fab")
		)
		(pad "1" smd circle
			(at -0.40005 0 270)
			(size 0 0)
			(layers "F.Cu" "F.Mask" "F.Paste")
			(net "PCEPLL6_VDDA18_PEX0")
		)
		(pad "2" smd circle
			(at 0.40005 0 270)
			(size 0 0)
			(layers "F.Cu" "F.Mask" "F.Paste")
			(net "PCEPLL6_VDDA18_PEX0_R")
		)
	)
	(footprint ""
		(layer "F.Cu")
		(at 13.0175 -312.137552)
		(property "Reference" "PC206"
			(at 0 0 0)
			(layer "F.SilkS")
			(hide yes)
			(effects
				(font
					(size 1.27 1.27)
				)
			)
		)
		(property "Value" ""
			(at 0 0 0)
			(layer "F.Fab")
			(effects
				(font
					(size 1.27 1.27)
				)
			)
		)
		(duplicate_pad_numbers_are_jumpers no)
		(fp_line
			(start -1.524 -0.762)
			(end 1.524 -0.762)
			(stroke
				(width 0.1524)
				(type default)
			)
			(layer "F.SilkS")
		)
		(fp_line
			(start -1.524 0.762)
			(end -1.524 -0.762)
			(stroke
				(width 0.1524)
				(type default)
			)
			(layer "F.SilkS")
		)
		(fp_line
			(start 1.524 -0.762)
			(end 1.524 0.762)
			(stroke
				(width 0.1524)
				(type default)
			)
			(layer "F.SilkS")
		)
		(fp_line
			(start 1.524 0.762)
			(end -1.524 0.762)
			(stroke
				(width 0.1524)
				(type default)
			)
			(layer "F.SilkS")
		)
		(fp_line
			(start -1.1049 -0.724916)
			(end -1.1049 0.724916)
			(stroke
				(width 0.1)
				(type default)
			)
			(layer "F.Fab")
		)
		(fp_line
			(start -1.1049 0.724916)
			(end 1.1049 0.724916)
			(stroke
				(width 0.1)
				(type default)
			)
			(layer "F.Fab")
		)
		(fp_line
			(start 1.1049 -0.724916)
			(end -1.1049 -0.724916)
			(stroke
				(width 0.1)
				(type default)
			)
			(layer "F.Fab")
		)
		(fp_line
			(start 1.1049 0.724916)
			(end 1.1049 -0.724916)
			(stroke
				(width 0.1)
				(type default)
			)
			(layer "F.Fab")
		)
		(pad "1" smd rect
			(at -0.889 0 180)
			(size 1.016 1.27)
			(layers "F.Cu" "F.Mask" "F.Paste")
			(net "SW_P12V_P1V25_PEX0_FLT")
		)
		(pad "2" smd rect
			(at 0.889 0 180)
			(size 1.016 1.27)
			(layers "F.Cu" "F.Mask" "F.Paste")
			(net "GND")
		)
	)
	(footprint ""
		(layer "F.Cu")
		(at 258.44373 -45.88891)
		(property "Reference" "R598"
			(at 0 0 0)
			(layer "F.SilkS")
			(hide yes)
			(effects
				(font
					(size 1.27 1.27)
				)
			)
		)
		(property "Value" ""
			(at 0 0 0)
			(layer "F.Fab")
			(effects
				(font
					(size 1.27 1.27)
				)
			)
		)
		(duplicate_pad_numbers_are_jumpers no)
		(fp_line
			(start -0.7874 -0.4064)
			(end 0.7874 -0.4064)
			(stroke
				(width 0.1524)
				(type default)
			)
			(layer "F.SilkS")
		)
		(fp_line
			(start -0.7874 0.4064)
			(end -0.7874 -0.4064)
			(stroke
				(width 0.1524)
				(type default)
			)
			(layer "F.SilkS")
		)
		(fp_line
			(start 0.7874 -0.4064)
			(end 0.7874 0.4064)
			(stroke
				(width 0.1524)
				(type default)
			)
			(layer "F.SilkS")
		)
		(fp_line
			(start 0.7874 0.4064)
			(end -0.7874 0.4064)
			(stroke
				(width 0.1524)
				(type default)
			)
			(layer "F.SilkS")
		)
		(fp_line
			(start -0.67945 -0.305054)
			(end -0.12065 -0.305054)
			(stroke
				(width 0.1)
				(type default)
			)
			(layer "F.Fab")
		)
		(fp_line
			(start -0.67945 0.3048)
			(end -0.67945 -0.305054)
			(stroke
				(width 0.1)
				(type default)
			)
			(layer "F.Fab")
		)
		(fp_line
			(start -0.12065 -0.305054)
			(end -0.12065 -0.2794)
			(stroke
				(width 0.1)
				(type default)
			)
			(layer "F.Fab")
		)
		(fp_line
			(start -0.12065 -0.2794)
			(end 0.12065 -0.2794)
			(stroke
				(width 0.1)
				(type default)
			)
			(layer "F.Fab")
		)
		(fp_line
			(start -0.12065 0.2794)
			(end -0.12065 0.3048)
			(stroke
				(width 0.1)
				(type default)
			)
			(layer "F.Fab")
		)
		(fp_line
			(start -0.12065 0.3048)
			(end -0.67945 0.3048)
			(stroke
				(width 0.1)
				(type default)
			)
			(layer "F.Fab")
		)
		(fp_line
			(start 0.120396 0.2794)
			(end -0.12065 0.2794)
			(stroke
				(width 0.1)
				(type default)
			)
			(layer "F.Fab")
		)
		(fp_line
			(start 0.120396 0.3048)
			(end 0.120396 0.2794)
			(stroke
				(width 0.1)
				(type default)
			)
			(layer "F.Fab")
		)
		(fp_line
			(start 0.12065 -0.3048)
			(end 0.67945 -0.3048)
			(stroke
				(width 0.1)
				(type default)
			)
			(layer "F.Fab")
		)
		(fp_line
			(start 0.12065 -0.2794)
			(end 0.12065 -0.3048)
			(stroke
				(width 0.1)
				(type default)
			)
			(layer "F.Fab")
		)
		(fp_line
			(start 0.67945 -0.3048)
			(end 0.67945 0.3048)
			(stroke
				(width 0.1)
				(type default)
			)
			(layer "F.Fab")
		)
		(fp_line
			(start 0.67945 0.3048)
			(end 0.120396 0.3048)
			(stroke
				(width 0.1)
				(type default)
			)
			(layer "F.Fab")
		)
		(pad "1" smd circle
			(at -0.40005 0)
			(size 0 0)
			(layers "F.Cu" "F.Mask" "F.Paste")
			(net "SSD8_ADC_A0")
		)
		(pad "2" smd circle
			(at 0.40005 0)
			(size 0 0)
			(layers "F.Cu" "F.Mask" "F.Paste")
			(net "GND")
		)
	)
	(footprint ""
		(layer "F.Cu")
		(at 84.023962 -343.952322 90)
		(property "Reference" "C108"
			(at 0 0 90)
			(layer "F.SilkS")
			(hide yes)
			(effects
				(font
					(size 1.27 1.27)
				)
			)
		)
		(property "Value" ""
			(at 0 0 90)
			(layer "F.Fab")
			(effects
				(font
					(size 1.27 1.27)
				)
			)
		)
		(duplicate_pad_numbers_are_jumpers no)
		(fp_line
			(start 0.299974 -0.150114)
			(end 0.299974 0.150114)
			(stroke
				(width 0.1)
				(type default)
			)
			(layer "F.Fab")
		)
		(fp_line
			(start -0.299974 -0.150114)
			(end 0.299974 -0.150114)
			(stroke
				(width 0.1)
				(type default)
			)
			(layer "F.Fab")
		)
		(fp_line
			(start 0.299974 0.150114)
			(end -0.299974 0.150114)
			(stroke
				(width 0.1)
				(type default)
			)
			(layer "F.Fab")
		)
		(fp_line
			(start -0.299974 0.150114)
			(end -0.299974 -0.150114)
			(stroke
				(width 0.1)
				(type default)
			)
			(layer "F.Fab")
		)
		(pad "1" smd rect
			(at -0.2667 0 90)
			(size 0.3048 0.381)
			(layers "F.Cu" "F.Mask" "F.Paste")
			(net "P5E_PEX0_STN5_TX_DN<90>")
		)
		(pad "2" smd rect
			(at 0.2667 0 90)
			(size 0.3048 0.381)
			(layers "F.Cu" "F.Mask" "F.Paste")
			(net "P5E_PEX0_STN5_TX_C_DN<90>")
		)
	)
	(footprint ""
		(layer "F.Cu")
		(at 358.41051 -125.979428)
		(property "Reference" "R883"
			(at 0 0 0)
			(layer "F.SilkS")
			(hide yes)
			(effects
				(font
					(size 1.27 1.27)
				)
			)
		)
		(property "Value" ""
			(at 0 0 0)
			(layer "F.Fab")
			(effects
				(font
					(size 1.27 1.27)
				)
			)
		)
		(duplicate_pad_numbers_are_jumpers no)
		(fp_line
			(start -0.7874 -0.4064)
			(end 0.7874 -0.4064)
			(stroke
				(width 0.1524)
				(type default)
			)
			(layer "F.SilkS")
		)
		(fp_line
			(start -0.7874 0.4064)
			(end -0.7874 -0.4064)
			(stroke
				(width 0.1524)
				(type default)
			)
			(layer "F.SilkS")
		)
		(fp_line
			(start 0.7874 -0.4064)
			(end 0.7874 0.4064)
			(stroke
				(width 0.1524)
				(type default)
			)
			(layer "F.SilkS")
		)
		(fp_line
			(start 0.7874 0.4064)
			(end -0.7874 0.4064)
			(stroke
				(width 0.1524)
				(type default)
			)
			(layer "F.SilkS")
		)
		(fp_line
			(start -0.67945 -0.305054)
			(end -0.12065 -0.305054)
			(stroke
				(width 0.1)
				(type default)
			)
			(layer "F.Fab")
		)
		(fp_line
			(start -0.67945 0.3048)
			(end -0.67945 -0.305054)
			(stroke
				(width 0.1)
				(type default)
			)
			(layer "F.Fab")
		)
		(fp_line
			(start -0.12065 -0.305054)
			(end -0.12065 -0.2794)
			(stroke
				(width 0.1)
				(type default)
			)
			(layer "F.Fab")
		)
		(fp_line
			(start -0.12065 -0.2794)
			(end 0.12065 -0.2794)
			(stroke
				(width 0.1)
				(type default)
			)
			(layer "F.Fab")
		)
		(fp_line
			(start -0.12065 0.2794)
			(end -0.12065 0.3048)
			(stroke
				(width 0.1)
				(type default)
			)
			(layer "F.Fab")
		)
		(fp_line
			(start -0.12065 0.3048)
			(end -0.67945 0.3048)
			(stroke
				(width 0.1)
				(type default)
			)
			(layer "F.Fab")
		)
		(fp_line
			(start 0.120396 0.2794)
			(end -0.12065 0.2794)
			(stroke
				(width 0.1)
				(type default)
			)
			(layer "F.Fab")
		)
		(fp_line
			(start 0.120396 0.3048)
			(end 0.120396 0.2794)
			(stroke
				(width 0.1)
				(type default)
			)
			(layer "F.Fab")
		)
		(fp_line
			(start 0.12065 -0.3048)
			(end 0.67945 -0.3048)
			(stroke
				(width 0.1)
				(type default)
			)
			(layer "F.Fab")
		)
		(fp_line
			(start 0.12065 -0.2794)
			(end 0.12065 -0.3048)
			(stroke
				(width 0.1)
				(type default)
			)
			(layer "F.Fab")
		)
		(fp_line
			(start 0.67945 -0.3048)
			(end 0.67945 0.3048)
			(stroke
				(width 0.1)
				(type default)
			)
			(layer "F.Fab")
		)
		(fp_line
			(start 0.67945 0.3048)
			(end 0.120396 0.3048)
			(stroke
				(width 0.1)
				(type default)
			)
			(layer "F.Fab")
		)
		(pad "1" smd circle
			(at -0.40005 0)
			(size 0 0)
			(layers "F.Cu" "F.Mask" "F.Paste")
			(net "P3V3_NIC6")
		)
		(pad "2" smd circle
			(at 0.40005 0)
			(size 0 0)
			(layers "F.Cu" "F.Mask" "F.Paste")
			(net "PWRGD_P3V3_NIC6")
		)
	)
	(footprint ""
		(layer "F.Cu")
		(at 55.88 -139.6492)
		(property "Reference" "R7"
			(at 0 0 0)
			(layer "F.SilkS")
			(hide yes)
			(effects
				(font
					(size 1.27 1.27)
				)
			)
		)
		(property "Value" ""
			(at 0 0 0)
			(layer "F.Fab")
			(effects
				(font
					(size 1.27 1.27)
				)
			)
		)
		(duplicate_pad_numbers_are_jumpers no)
		(fp_line
			(start -0.7874 -0.4064)
			(end 0.7874 -0.4064)
			(stroke
				(width 0.1524)
				(type default)
			)
			(layer "F.SilkS")
		)
		(fp_line
			(start -0.7874 0.4064)
			(end -0.7874 -0.4064)
			(stroke
				(width 0.1524)
				(type default)
			)
			(layer "F.SilkS")
		)
		(fp_line
			(start 0.7874 -0.4064)
			(end 0.7874 0.4064)
			(stroke
				(width 0.1524)
				(type default)
			)
			(layer "F.SilkS")
		)
		(fp_line
			(start 0.7874 0.4064)
			(end -0.7874 0.4064)
			(stroke
				(width 0.1524)
				(type default)
			)
			(layer "F.SilkS")
		)
		(fp_line
			(start -0.67945 -0.305054)
			(end -0.12065 -0.305054)
			(stroke
				(width 0.1)
				(type default)
			)
			(layer "F.Fab")
		)
		(fp_line
			(start -0.67945 0.3048)
			(end -0.67945 -0.305054)
			(stroke
				(width 0.1)
				(type default)
			)
			(layer "F.Fab")
		)
		(fp_line
			(start -0.12065 -0.305054)
			(end -0.12065 -0.2794)
			(stroke
				(width 0.1)
				(type default)
			)
			(layer "F.Fab")
		)
		(fp_line
			(start -0.12065 -0.2794)
			(end 0.12065 -0.2794)
			(stroke
				(width 0.1)
				(type default)
			)
			(layer "F.Fab")
		)
		(fp_line
			(start -0.12065 0.2794)
			(end -0.12065 0.3048)
			(stroke
				(width 0.1)
				(type default)
			)
			(layer "F.Fab")
		)
		(fp_line
			(start -0.12065 0.3048)
			(end -0.67945 0.3048)
			(stroke
				(width 0.1)
				(type default)
			)
			(layer "F.Fab")
		)
		(fp_line
			(start 0.120396 0.2794)
			(end -0.12065 0.2794)
			(stroke
				(width 0.1)
				(type default)
			)
			(layer "F.Fab")
		)
		(fp_line
			(start 0.120396 0.3048)
			(end 0.120396 0.2794)
			(stroke
				(width 0.1)
				(type default)
			)
			(layer "F.Fab")
		)
		(fp_line
			(start 0.12065 -0.3048)
			(end 0.67945 -0.3048)
			(stroke
				(width 0.1)
				(type default)
			)
			(layer "F.Fab")
		)
		(fp_line
			(start 0.12065 -0.2794)
			(end 0.12065 -0.3048)
			(stroke
				(width 0.1)
				(type default)
			)
			(layer "F.Fab")
		)
		(fp_line
			(start 0.67945 -0.3048)
			(end 0.67945 0.3048)
			(stroke
				(width 0.1)
				(type default)
			)
			(layer "F.Fab")
		)
		(fp_line
			(start 0.67945 0.3048)
			(end 0.120396 0.3048)
			(stroke
				(width 0.1)
				(type default)
			)
			(layer "F.Fab")
		)
		(pad "1" smd circle
			(at -0.40005 0)
			(size 0 0)
			(layers "F.Cu" "F.Mask" "F.Paste")
			(net "PRSNTB2_NIC0_N")
		)
		(pad "2" smd circle
			(at 0.40005 0)
			(size 0 0)
			(layers "F.Cu" "F.Mask" "F.Paste")
			(net "P3V3_AUX")
		)
	)
	(footprint ""
		(layer "F.Cu")
		(at 144.149318 -300.197012 -90)
		(property "Reference" "C3212"
			(at 0 0 270)
			(layer "F.SilkS")
			(hide yes)
			(effects
				(font
					(size 1.27 1.27)
				)
			)
		)
		(property "Value" ""
			(at 0 0 270)
			(layer "F.Fab")
			(effects
				(font
					(size 1.27 1.27)
				)
			)
		)
		(duplicate_pad_numbers_are_jumpers no)
		(fp_line
			(start -0.299974 0.150114)
			(end -0.299974 -0.150114)
			(stroke
				(width 0.1)
				(type default)
			)
			(layer "F.Fab")
		)
		(fp_line
			(start 0.299974 0.150114)
			(end -0.299974 0.150114)
			(stroke
				(width 0.1)
				(type default)
			)
			(layer "F.Fab")
		)
		(fp_line
			(start -0.299974 -0.150114)
			(end 0.299974 -0.150114)
			(stroke
				(width 0.1)
				(type default)
			)
			(layer "F.Fab")
		)
		(fp_line
			(start 0.299974 -0.150114)
			(end 0.299974 0.150114)
			(stroke
				(width 0.1)
				(type default)
			)
			(layer "F.Fab")
		)
		(pad "1" smd rect
			(at -0.2667 0 270)
			(size 0.3048 0.381)
			(layers "F.Cu" "F.Mask" "F.Paste")
			(net "P1V8_PLL0_PEX1")
		)
		(pad "2" smd rect
			(at 0.2667 0 270)
			(size 0.3048 0.381)
			(layers "F.Cu" "F.Mask" "F.Paste")
			(net "GND")
		)
	)
)
